(kicad_pcb
	(version 20211014)
	(generator pcbnew)
	(general
    (thickness 1.6)
  )
	(paper "A4")
	(title_block
    (title "SA800U (Snapdragon 845) Baseboard")
    (date "2023-10-19")
    (rev "1.0.3")
    (company "Antmicro Ltd.")
    (comment 1 "www.antmicro.com")
		(comment 9 "footprints 491-505 of 589")
	)
	(layers
    (0 "F.Cu" signal)
    (1 "In1.Cu" power)
    (2 "In2.Cu" signal)
    (3 "In3.Cu" signal)
    (4 "In4.Cu" power)
    (31 "B.Cu" signal)
    (32 "B.Adhes" user "B.Adhesive")
    (33 "F.Adhes" user "F.Adhesive")
    (34 "B.Paste" user)
    (35 "F.Paste" user)
    (36 "B.SilkS" user "B.Silkscreen")
    (37 "F.SilkS" user "F.Silkscreen")
    (38 "B.Mask" user)
    (39 "F.Mask" user)
    (40 "Dwgs.User" user "User.Drawings")
    (41 "Cmts.User" user "User.Comments")
    (42 "Eco1.User" user "User.Eco1")
    (43 "Eco2.User" user "User.Eco2")
    (44 "Edge.Cuts" user)
    (45 "Margin" user)
    (46 "B.CrtYd" user "B.Courtyard")
    (47 "F.CrtYd" user "F.Courtyard")
    (48 "B.Fab" user)
    (49 "F.Fab" user)
  )
	(footprint "sa800u-baseboard-hw-footprints:TP_SMD_0.75mm" (layer "B.Cu")
    (tedit 5E4A9375)
    (at 103.8 100.4)
    (property "Author" "Antmicro")
    (property "License" "Apache-2.0")
    (property "MPN" "")
    (property "Manufacturer" "")
    (property "Sheetfile" "ethernet-controller.kicad_sch")
    (property "Sheetname" "Ethernet Controller")
    (attr smd)
    (fp_text reference "TP2" (at 2.32 0.49 180) (layer "B.SilkS")
      (effects (font (size 0.7 0.7) (thickness 0.15)) (justify left bottom mirror))
    )
    (fp_text value "TP_0.75mm_SMD" (at 0 -1.2 180) (layer "B.Fab")
      (effects (font (size 0.7 0.7) (thickness 0.15)) (justify left bottom mirror))
    )
    (fp_text user "License: Apache-2.0" (at -0.4 -5.101 180) (layer "B.Fab") hide
      (effects (font (size 0.7 0.7) (thickness 0.15)) (justify left bottom mirror))
    )
    (fp_text user "${REFERENCE}" (at -0.4 -2.7 180) (layer "B.Fab") hide
      (effects (font (size 0.7 0.7) (thickness 0.15)) (justify left bottom mirror))
    )
    (fp_text user "Author: Antmicro" (at -0.4 -3.901 180) (layer "B.Fab") hide
      (effects (font (size 0.7 0.7) (thickness 0.15)) (justify left bottom mirror))
    )
    (pad "1" smd circle (at 0 0) (size 0.75 0.75) (layers "B.Cu" "B.Mask")
      (net 162 "PCIE1_CLKREQ_N") (pinfunction "1") (pintype "passive"))
  )
	(footprint "sa800u-baseboard-hw-footprints:TP_SMD_0.75mm" (layer "B.Cu")
    (tedit 5E4A9375)
    (at 105 103.2)
    (property "Author" "Antmicro")
    (property "License" "Apache-2.0")
    (property "MPN" "")
    (property "Manufacturer" "")
    (property "Sheetfile" "ethernet-controller.kicad_sch")
    (property "Sheetname" "Ethernet Controller")
    (attr smd)
    (fp_text reference "TP3" (at 2.37 0.43 180) (layer "B.SilkS")
      (effects (font (size 0.7 0.7) (thickness 0.15)) (justify left bottom mirror))
    )
    (fp_text value "TP_0.75mm_SMD" (at 0 -1.2 180) (layer "B.Fab")
      (effects (font (size 0.7 0.7) (thickness 0.15)) (justify left bottom mirror))
    )
    (fp_text user "Author: Antmicro" (at -0.4 -3.901 180) (layer "B.Fab") hide
      (effects (font (size 0.7 0.7) (thickness 0.15)) (justify left bottom mirror))
    )
    (fp_text user "${REFERENCE}" (at -0.4 -2.7 180) (layer "B.Fab") hide
      (effects (font (size 0.7 0.7) (thickness 0.15)) (justify left bottom mirror))
    )
    (fp_text user "License: Apache-2.0" (at -0.4 -5.101 180) (layer "B.Fab") hide
      (effects (font (size 0.7 0.7) (thickness 0.15)) (justify left bottom mirror))
    )
    (pad "1" smd circle (at 0 0) (size 0.75 0.75) (layers "B.Cu" "B.Mask")
      (net 286 "/Ethernet Controller/ETH_ISOLATEB") (pinfunction "1") (pintype "passive"))
  )
	(footprint "sa800u-baseboard-hw-footprints:TP_SMD_0.75mm" (layer "B.Cu")
    (tedit 5E4A9375)
    (at 102.6 99.4)
    (property "Author" "Antmicro")
    (property "License" "Apache-2.0")
    (property "MPN" "")
    (property "Manufacturer" "")
    (property "Sheetfile" "ethernet-controller.kicad_sch")
    (property "Sheetname" "Ethernet Controller")
    (attr smd)
    (fp_text reference "TP4" (at 2.36 0.31 180) (layer "B.SilkS")
      (effects (font (size 0.7 0.7) (thickness 0.15)) (justify left bottom mirror))
    )
    (fp_text value "TP_0.75mm_SMD" (at 0 -1.2 180) (layer "B.Fab")
      (effects (font (size 0.7 0.7) (thickness 0.15)) (justify left bottom mirror))
    )
    (fp_text user "Author: Antmicro" (at -0.4 -3.901 180) (layer "B.Fab") hide
      (effects (font (size 0.7 0.7) (thickness 0.15)) (justify left bottom mirror))
    )
    (fp_text user "${REFERENCE}" (at -0.4 -2.7 180) (layer "B.Fab") hide
      (effects (font (size 0.7 0.7) (thickness 0.15)) (justify left bottom mirror))
    )
    (fp_text user "License: Apache-2.0" (at -0.4 -5.101 180) (layer "B.Fab") hide
      (effects (font (size 0.7 0.7) (thickness 0.15)) (justify left bottom mirror))
    )
    (pad "1" smd circle (at 0 0) (size 0.75 0.75) (layers "B.Cu" "B.Mask")
      (net 161 "PCIE1_WAKE_N") (pinfunction "1") (pintype "passive"))
  )
	(footprint "sa800u-baseboard-hw-footprints:TP_SMD_0.75mm" (layer "B.Cu")
    (tedit 5E4A9375)
    (at 104.8 101.6)
    (property "Author" "Antmicro")
    (property "License" "Apache-2.0")
    (property "MPN" "")
    (property "Manufacturer" "")
    (property "Sheetfile" "ethernet-controller.kicad_sch")
    (property "Sheetname" "Ethernet Controller")
    (attr smd)
    (fp_text reference "TP5" (at 2.39 0.39 180) (layer "B.SilkS")
      (effects (font (size 0.7 0.7) (thickness 0.15)) (justify left bottom mirror))
    )
    (fp_text value "TP_0.75mm_SMD" (at 0 -1.2 180) (layer "B.Fab")
      (effects (font (size 0.7 0.7) (thickness 0.15)) (justify left bottom mirror))
    )
    (fp_text user "${REFERENCE}" (at -0.4 -2.7 180) (layer "B.Fab") hide
      (effects (font (size 0.7 0.7) (thickness 0.15)) (justify left bottom mirror))
    )
    (fp_text user "License: Apache-2.0" (at -0.4 -5.101 180) (layer "B.Fab") hide
      (effects (font (size 0.7 0.7) (thickness 0.15)) (justify left bottom mirror))
    )
    (fp_text user "Author: Antmicro" (at -0.4 -3.901 180) (layer "B.Fab") hide
      (effects (font (size 0.7 0.7) (thickness 0.15)) (justify left bottom mirror))
    )
    (pad "1" smd circle (at 0 0) (size 0.75 0.75) (layers "B.Cu" "B.Mask")
      (net 163 "PCIE1_RST_N") (pinfunction "1") (pintype "passive"))
  )
	(footprint "sa800u-baseboard-hw-footprints:TP_SMD_0.75mm" (layer "B.Cu")
    (tedit 5E4A9375)
    (at 92.8 106.6)
    (property "Author" "Antmicro")
    (property "License" "Apache-2.0")
    (property "MPN" "")
    (property "Manufacturer" "")
    (property "Sheetfile" "ethernet-controller.kicad_sch")
    (property "Sheetname" "Ethernet Controller")
    (attr smd)
    (fp_text reference "TP6" (at -0.3 0.27 180) (layer "B.SilkS")
      (effects (font (size 0.7 0.7) (thickness 0.15)) (justify left bottom mirror))
    )
    (fp_text value "TP_0.75mm_SMD" (at 0 -1.2 180) (layer "B.Fab")
      (effects (font (size 0.7 0.7) (thickness 0.15)) (justify left bottom mirror))
    )
    (fp_text user "${REFERENCE}" (at -0.4 -2.7 180) (layer "B.Fab") hide
      (effects (font (size 0.7 0.7) (thickness 0.15)) (justify left bottom mirror))
    )
    (fp_text user "License: Apache-2.0" (at -0.4 -5.101 180) (layer "B.Fab") hide
      (effects (font (size 0.7 0.7) (thickness 0.15)) (justify left bottom mirror))
    )
    (fp_text user "Author: Antmicro" (at -0.4 -3.901 180) (layer "B.Fab") hide
      (effects (font (size 0.7 0.7) (thickness 0.15)) (justify left bottom mirror))
    )
    (pad "1" smd circle (at 0 0) (size 0.75 0.75) (layers "B.Cu" "B.Mask")
      (net 393 "Net-(R11-Pad1)") (pinfunction "1") (pintype "passive"))
  )
	(footprint "sa800u-baseboard-hw-footprints:TP_SMD_0.75mm" (layer "B.Cu")
    (tedit 5E4A9375)
    (at 100.6 107.8)
    (property "Author" "Antmicro")
    (property "License" "Apache-2.0")
    (property "MPN" "")
    (property "Manufacturer" "")
    (property "Sheetfile" "ethernet-controller.kicad_sch")
    (property "Sheetname" "Ethernet Controller")
    (attr smd)
    (fp_text reference "TP7" (at 2.48 0.56 180) (layer "B.SilkS")
      (effects (font (size 0.7 0.7) (thickness 0.15)) (justify left bottom mirror))
    )
    (fp_text value "TP_0.75mm_SMD" (at 0 -1.2 180) (layer "B.Fab")
      (effects (font (size 0.7 0.7) (thickness 0.15)) (justify left bottom mirror))
    )
    (fp_text user "License: Apache-2.0" (at -0.4 -5.101 180) (layer "B.Fab") hide
      (effects (font (size 0.7 0.7) (thickness 0.15)) (justify left bottom mirror))
    )
    (fp_text user "${REFERENCE}" (at -0.4 -2.7 180) (layer "B.Fab") hide
      (effects (font (size 0.7 0.7) (thickness 0.15)) (justify left bottom mirror))
    )
    (fp_text user "Author: Antmicro" (at -0.4 -3.901 180) (layer "B.Fab") hide
      (effects (font (size 0.7 0.7) (thickness 0.15)) (justify left bottom mirror))
    )
    (pad "1" smd circle (at 0 0) (size 0.75 0.75) (layers "B.Cu" "B.Mask")
      (net 178 "/Ethernet Controller/REG_1V0") (pinfunction "1") (pintype "passive"))
  )
	(footprint "sa800u-baseboard-hw-footprints:TP_SMD_0.75mm" (layer "B.Cu")
    (tedit 5E4A9375)
    (at 94.4 100)
    (property "Author" "Antmicro")
    (property "License" "Apache-2.0")
    (property "MPN" "")
    (property "Manufacturer" "")
    (property "Sheetfile" "ethernet-controller.kicad_sch")
    (property "Sheetname" "Ethernet Controller")
    (attr smd)
    (fp_text reference "TP8" (at 0.53 -0.47 180) (layer "B.SilkS")
      (effects (font (size 0.7 0.7) (thickness 0.15)) (justify left bottom mirror))
    )
    (fp_text value "TP_0.75mm_SMD" (at 0 -1.2 180) (layer "B.Fab")
      (effects (font (size 0.7 0.7) (thickness 0.15)) (justify left bottom mirror))
    )
    (fp_text user "License: Apache-2.0" (at -0.4 -5.101 180) (layer "B.Fab") hide
      (effects (font (size 0.7 0.7) (thickness 0.15)) (justify left bottom mirror))
    )
    (fp_text user "Author: Antmicro" (at -0.4 -3.901 180) (layer "B.Fab") hide
      (effects (font (size 0.7 0.7) (thickness 0.15)) (justify left bottom mirror))
    )
    (fp_text user "${REFERENCE}" (at -0.4 -2.7 180) (layer "B.Fab") hide
      (effects (font (size 0.7 0.7) (thickness 0.15)) (justify left bottom mirror))
    )
    (pad "1" smd circle (at 0 0) (size 0.75 0.75) (layers "B.Cu" "B.Mask")
      (net 181 "/Ethernet Controller/ETH_1V0") (pinfunction "1") (pintype "passive"))
  )
	(footprint "sa800u-baseboard-hw-footprints:TP_SMD_0.75mm" (layer "B.Cu")
    (tedit 5E4A9375)
    (at 140.25 126.5)
    (property "Author" "Antmicro")
    (property "License" "Apache-2.0")
    (property "MPN" "")
    (property "Manufacturer" "")
    (property "Sheetfile" "hdmi-converter.kicad_sch")
    (property "Sheetname" "HDMI converter")
    (attr smd)
    (fp_text reference "TP9" (at 0.93 1.2 180) (layer "B.SilkS")
      (effects (font (size 0.7 0.7) (thickness 0.15)) (justify left bottom mirror))
    )
    (fp_text value "TP_0.75mm_SMD" (at 0 -1.2 180) (layer "B.Fab")
      (effects (font (size 0.7 0.7) (thickness 0.15)) (justify left bottom mirror))
    )
    (fp_text user "Author: Antmicro" (at -0.4 -3.901 180) (layer "B.Fab") hide
      (effects (font (size 0.7 0.7) (thickness 0.15)) (justify left bottom mirror))
    )
    (fp_text user "${REFERENCE}" (at -0.4 -2.7 180) (layer "B.Fab") hide
      (effects (font (size 0.7 0.7) (thickness 0.15)) (justify left bottom mirror))
    )
    (fp_text user "License: Apache-2.0" (at -0.4 -5.101 180) (layer "B.Fab") hide
      (effects (font (size 0.7 0.7) (thickness 0.15)) (justify left bottom mirror))
    )
    (pad "1" smd circle (at 0 0) (size 0.75 0.75) (layers "B.Cu" "B.Mask")
      (net 289 "/HDMI converter/I2C_ADDR") (pinfunction "1") (pintype "passive"))
  )
	(footprint "sa800u-baseboard-hw-footprints:TP_SMD_0.75mm" (layer "B.Cu")
    (tedit 5E4A9375)
    (at 135.9 127.1992)
    (property "Author" "Antmicro")
    (property "License" "Apache-2.0")
    (property "MPN" "")
    (property "Manufacturer" "")
    (property "Sheetfile" "hdmi-converter.kicad_sch")
    (property "Sheetname" "HDMI converter")
    (attr smd)
    (fp_text reference "TP10" (at -0.17 -0.1092 180) (layer "B.SilkS")
      (effects (font (size 0.7 0.7) (thickness 0.15)) (justify left bottom mirror))
    )
    (fp_text value "TP_0.75mm_SMD" (at 0 -1.2 180) (layer "B.Fab")
      (effects (font (size 0.7 0.7) (thickness 0.15)) (justify left bottom mirror))
    )
    (fp_text user "License: Apache-2.0" (at -0.4 -5.101 180) (layer "B.Fab") hide
      (effects (font (size 0.7 0.7) (thickness 0.15)) (justify left bottom mirror))
    )
    (fp_text user "Author: Antmicro" (at -0.4 -3.901 180) (layer "B.Fab") hide
      (effects (font (size 0.7 0.7) (thickness 0.15)) (justify left bottom mirror))
    )
    (fp_text user "${REFERENCE}" (at -0.4 -2.7 180) (layer "B.Fab") hide
      (effects (font (size 0.7 0.7) (thickness 0.15)) (justify left bottom mirror))
    )
    (pad "1" smd circle (at 0 0) (size 0.75 0.75) (layers "B.Cu" "B.Mask")
      (net 184 "/HDMI converter/LT9611_VCC33_IO") (pinfunction "1") (pintype "passive"))
  )
	(footprint "sa800u-baseboard-hw-footprints:TP_SMD_0.75mm" (layer "B.Cu")
    (tedit 5E4A9375)
    (at 146.75 122.25)
    (property "Author" "Antmicro")
    (property "License" "Apache-2.0")
    (property "MPN" "")
    (property "Manufacturer" "")
    (property "Sheetfile" "hdmi-converter.kicad_sch")
    (property "Sheetname" "HDMI converter")
    (attr smd)
    (fp_text reference "TP12" (at 2.3 -0.5 180) (layer "B.SilkS")
      (effects (font (size 0.7 0.7) (thickness 0.15)) (justify left bottom mirror))
    )
    (fp_text value "TP_0.75mm_SMD" (at 0 -1.2 180) (layer "B.Fab")
      (effects (font (size 0.7 0.7) (thickness 0.15)) (justify left bottom mirror))
    )
    (fp_text user "${REFERENCE}" (at -0.4 -2.7 180) (layer "B.Fab") hide
      (effects (font (size 0.7 0.7) (thickness 0.15)) (justify left bottom mirror))
    )
    (fp_text user "License: Apache-2.0" (at -0.4 -5.101 180) (layer "B.Fab") hide
      (effects (font (size 0.7 0.7) (thickness 0.15)) (justify left bottom mirror))
    )
    (fp_text user "Author: Antmicro" (at -0.4 -3.901 180) (layer "B.Fab") hide
      (effects (font (size 0.7 0.7) (thickness 0.15)) (justify left bottom mirror))
    )
    (pad "1" smd circle (at 0 0) (size 0.75 0.75) (layers "B.Cu" "B.Mask")
      (net 185 "/HDMI converter/LT9611_VCC33_RX") (pinfunction "1") (pintype "passive"))
  )
	(footprint "sa800u-baseboard-hw-footprints:TP_SMD_0.75mm" (layer "B.Cu")
    (tedit 5E4A9375)
    (at 141.3 132.7492)
    (property "Author" "Antmicro")
    (property "License" "Apache-2.0")
    (property "MPN" "")
    (property "Manufacturer" "")
    (property "Sheetfile" "hdmi-converter.kicad_sch")
    (property "Sheetname" "HDMI converter")
    (attr smd)
    (fp_text reference "TP11" (at 0.42 0.3208 270) (layer "B.SilkS")
      (effects (font (size 0.7 0.7) (thickness 0.15)) (justify left bottom mirror))
    )
    (fp_text value "TP_0.75mm_SMD" (at 0 -1.2 180) (layer "B.Fab")
      (effects (font (size 0.7 0.7) (thickness 0.15)) (justify left bottom mirror))
    )
    (fp_text user "${REFERENCE}" (at -0.4 -2.7 180) (layer "B.Fab") hide
      (effects (font (size 0.7 0.7) (thickness 0.15)) (justify left bottom mirror))
    )
    (fp_text user "License: Apache-2.0" (at -0.4 -5.101 180) (layer "B.Fab") hide
      (effects (font (size 0.7 0.7) (thickness 0.15)) (justify left bottom mirror))
    )
    (fp_text user "Author: Antmicro" (at -0.4 -3.901 180) (layer "B.Fab") hide
      (effects (font (size 0.7 0.7) (thickness 0.15)) (justify left bottom mirror))
    )
    (pad "1" smd circle (at 0 0) (size 0.75 0.75) (layers "B.Cu" "B.Mask")
      (net 187 "/HDMI converter/LT9611_VCC33_TX") (pinfunction "1") (pintype "passive"))
  )
	(footprint "sa800u-baseboard-hw-footprints:TP_SMD_0.75mm" (layer "B.Cu")
    (tedit 5E4A9375)
    (at 142 123.5)
    (property "Author" "Antmicro")
    (property "License" "Apache-2.0")
    (property "MPN" "")
    (property "Manufacturer" "")
    (property "Sheetfile" "hdmi-converter.kicad_sch")
    (property "Sheetname" "HDMI converter")
    (attr smd)
    (fp_text reference "TP18" (at 0.53 -0.44 180) (layer "B.SilkS")
      (effects (font (size 0.7 0.7) (thickness 0.15)) (justify left bottom mirror))
    )
    (fp_text value "TP_0.75mm_SMD" (at 0 -1.2 180) (layer "B.Fab")
      (effects (font (size 0.7 0.7) (thickness 0.15)) (justify left bottom mirror))
    )
    (fp_text user "License: Apache-2.0" (at -0.4 -5.101 180) (layer "B.Fab") hide
      (effects (font (size 0.7 0.7) (thickness 0.15)) (justify left bottom mirror))
    )
    (fp_text user "Author: Antmicro" (at -0.4 -3.901 180) (layer "B.Fab") hide
      (effects (font (size 0.7 0.7) (thickness 0.15)) (justify left bottom mirror))
    )
    (fp_text user "${REFERENCE}" (at -0.4 -2.7 180) (layer "B.Fab") hide
      (effects (font (size 0.7 0.7) (thickness 0.15)) (justify left bottom mirror))
    )
    (pad "1" smd circle (at 0 0) (size 0.75 0.75) (layers "B.Cu" "B.Mask")
      (net 186 "/HDMI converter/LT9611_RST_N") (pinfunction "1") (pintype "passive"))
  )
	(footprint "sa800u-baseboard-hw-footprints:TP_SMD_0.75mm" (layer "B.Cu")
    (tedit 5E4A9375)
    (at 140.2 123.5)
    (property "Author" "Antmicro")
    (property "License" "Apache-2.0")
    (property "MPN" "")
    (property "Manufacturer" "")
    (property "Sheetfile" "hdmi-converter.kicad_sch")
    (property "Sheetname" "HDMI converter")
    (attr smd)
    (fp_text reference "TP17" (at -0.28 0.4 180) (layer "B.SilkS")
      (effects (font (size 0.7 0.7) (thickness 0.15)) (justify left bottom mirror))
    )
    (fp_text value "TP_0.75mm_SMD" (at 0 -1.2 180) (layer "B.Fab")
      (effects (font (size 0.7 0.7) (thickness 0.15)) (justify left bottom mirror))
    )
    (fp_text user "${REFERENCE}" (at -0.4 -2.7 180) (layer "B.Fab") hide
      (effects (font (size 0.7 0.7) (thickness 0.15)) (justify left bottom mirror))
    )
    (fp_text user "License: Apache-2.0" (at -0.4 -5.101 180) (layer "B.Fab") hide
      (effects (font (size 0.7 0.7) (thickness 0.15)) (justify left bottom mirror))
    )
    (fp_text user "Author: Antmicro" (at -0.4 -3.901 180) (layer "B.Fab") hide
      (effects (font (size 0.7 0.7) (thickness 0.15)) (justify left bottom mirror))
    )
    (pad "1" smd circle (at 0 0) (size 0.75 0.75) (layers "B.Cu" "B.Mask")
      (net 284 "/HDMI converter/LT9611_INTO_GPIO5") (pinfunction "1") (pintype "passive"))
  )
	(footprint "sa800u-baseboard-hw-footprints:TP_SMD_0.75mm" (layer "B.Cu")
    (tedit 5E4A9375)
    (at 136.25 128.75)
    (property "Author" "Antmicro")
    (property "License" "Apache-2.0")
    (property "MPN" "")
    (property "Manufacturer" "")
    (property "Sheetfile" "hdmi-converter.kicad_sch")
    (property "Sheetname" "HDMI converter")
    (attr smd)
    (fp_text reference "TP13" (at -0.25 0.3 180) (layer "B.SilkS")
      (effects (font (size 0.7 0.7) (thickness 0.15)) (justify left bottom mirror))
    )
    (fp_text value "TP_0.75mm_SMD" (at 0 -1.2 180) (layer "B.Fab")
      (effects (font (size 0.7 0.7) (thickness 0.15)) (justify left bottom mirror))
    )
    (fp_text user "${REFERENCE}" (at -0.4 -2.7 180) (layer "B.Fab") hide
      (effects (font (size 0.7 0.7) (thickness 0.15)) (justify left bottom mirror))
    )
    (fp_text user "License: Apache-2.0" (at -0.4 -5.101 180) (layer "B.Fab") hide
      (effects (font (size 0.7 0.7) (thickness 0.15)) (justify left bottom mirror))
    )
    (fp_text user "Author: Antmicro" (at -0.4 -3.901 180) (layer "B.Fab") hide
      (effects (font (size 0.7 0.7) (thickness 0.15)) (justify left bottom mirror))
    )
    (pad "1" smd circle (at 0 0) (size 0.75 0.75) (layers "B.Cu" "B.Mask")
      (net 188 "/HDMI converter/LT9611_VDD12") (pinfunction "1") (pintype "passive"))
  )
	(footprint "sa800u-baseboard-hw-footprints:TP_SMD_0.75mm" (layer "B.Cu")
    (tedit 5E4A9375)
    (at 146 120.9)
    (property "Author" "Antmicro")
    (property "License" "Apache-2.0")
    (property "MPN" "")
    (property "Manufacturer" "")
    (property "Sheetfile" "hdmi-converter.kicad_sch")
    (property "Sheetname" "HDMI converter")
    (attr smd)
    (fp_text reference "TP14" (at 2.24 -0.49 180) (layer "B.SilkS")
      (effects (font (size 0.7 0.7) (thickness 0.15)) (justify left bottom mirror))
    )
    (fp_text value "TP_0.75mm_SMD" (at 0 -1.2 180) (layer "B.Fab")
      (effects (font (size 0.7 0.7) (thickness 0.15)) (justify left bottom mirror))
    )
    (fp_text user "${REFERENCE}" (at -0.4 -2.7 180) (layer "B.Fab") hide
      (effects (font (size 0.7 0.7) (thickness 0.15)) (justify left bottom mirror))
    )
    (fp_text user "Author: Antmicro" (at -0.4 -3.901 180) (layer "B.Fab") hide
      (effects (font (size 0.7 0.7) (thickness 0.15)) (justify left bottom mirror))
    )
    (fp_text user "License: Apache-2.0" (at -0.4 -5.101 180) (layer "B.Fab") hide
      (effects (font (size 0.7 0.7) (thickness 0.15)) (justify left bottom mirror))
    )
    (pad "1" smd circle (at 0 0) (size 0.75 0.75) (layers "B.Cu" "B.Mask")
      (net 189 "/HDMI converter/LT9611_VCC12_RX") (pinfunction "1") (pintype "passive"))
  )
)
